(kicad_pcb
	(version 20260206)
	(generator "pcbnew")
	(generator_version "10.0")
	(general
		(thickness 1.6)
		(legacy_teardrops no)
	)
	(paper "A4")
	(title_block
		(title "9054_F0T_PDB_BD_GPU_F_V04_1213_1550_OCP.brd")
		(comment 1 "Grand Teton / footprints 332-335 of 608")
	)
	(layers
		(0 "F.Cu" signal "TOP")
		(4 "In1.Cu" signal "GND")
		(6 "In2.Cu" signal "IN1")
		(8 "In3.Cu" signal "GND1")
		(10 "In4.Cu" signal "VCC")
		(12 "In5.Cu" signal "VCC1")
		(14 "In6.Cu" signal "GND2")
		(16 "In7.Cu" signal "IN2")
		(18 "In8.Cu" signal "GND3")
		(2 "B.Cu" signal "BOTTOM")
		(9 "F.Adhes" user "F.Adhesive")
		(11 "B.Adhes" user "B.Adhesive")
		(13 "F.Paste" user "Package Geometry/Pastemask Top")
		(15 "B.Paste" user "Package Geometry/Pastemask Bottom")
		(5 "F.SilkS" user "Ref Des/Silkscreen Top")
		(7 "B.SilkS" user "Ref Des/Silkscreen Bottom")
		(1 "F.Mask" user "Board Geometry/Soldermask Top")
		(3 "B.Mask" user "Board Geometry/Soldermask Bottom")
		(17 "Dwgs.User" user "User.Drawings")
		(19 "Cmts.User" user "User.Comments")
		(21 "Eco1.User" user "User.Eco1")
		(23 "Eco2.User" user "User.Eco2")
		(25 "Edge.Cuts" user "Board Geometry/Outline")
		(27 "Margin" user)
		(31 "F.CrtYd" user "Package Geometry/Place Bound Top")
		(29 "B.CrtYd" user "Package Geometry/Place Bound Bottom")
		(35 "F.Fab" user "Ref Des/Assembly Top")
		(33 "B.Fab" user "Ref Des/Assembly Bottom")
	)
	(footprint ""
		(layer "F.Cu")
		(at 378.079 -99.06)
		(property "Reference" "PC32"
			(at 5.1054 -4.79933 0)
			(unlocked yes)
			(layer "F.SilkS")
			(effects
				(font
					(size 0.7874 0.5842)
					(thickness 0.1524)
				)
				(justify left)
			)
		)
		(property "Value" ""
			(at 0 0 0)
			(layer "F.Fab")
			(effects
				(font
					(size 1.27 1.27)
				)
			)
		)
		(duplicate_pad_numbers_are_jumpers no)
		(fp_line
			(start -9.253728 3.750056)
			(end 9.249918 3.750056)
			(stroke
				(width 0.1524)
				(type default)
			)
			(layer "F.SilkS")
		)
		(fp_line
			(start 0 3.750056)
			(end -9.253728 3.750056)
			(stroke
				(width 0.1524)
				(type default)
			)
			(layer "F.SilkS")
		)
		(fp_circle
			(center 0 3.750056)
			(end 9.249918 3.750056)
			(stroke
				(width 0.1524)
				(type default)
			)
			(fill no)
			(layer "F.SilkS")
		)
		(fp_poly
			(pts
				(arc
					(start 9.249918 3.750056)
					(mid 0 12.999974)
					(end -9.249918 3.750056)
				)
			)
			(stroke
				(width 0)
				(type default)
			)
			(fill yes)
			(layer "F.SilkS")
		)
		(fp_circle
			(center 0 3.750056)
			(end 9.249918 3.750056)
			(stroke
				(width 0.1)
				(type default)
			)
			(fill no)
			(layer "F.Fab")
		)
		(pad "1" thru_hole rect
			(at 0 0)
			(size 1.778 1.778)
			(drill 1.27)
			(layers "*.Cu" "*.Mask")
			(remove_unused_layers no)
			(net "P52V_HS1")
			(clearance 0)
			(padstack
				(mode front_inner_back)
				(layer "Inner"
					(shape circle)
					(size 1.778 1.778)
					(clearance 0)
				)
				(layer "B.Cu"
					(shape rect)
					(size 1.778 1.778)
					(clearance 0)
				)
			)
		)
		(pad "2" thru_hole circle
			(at 0 7.500112)
			(size 1.778 1.778)
			(drill 1.27)
			(layers "*.Cu" "*.Mask")
			(remove_unused_layers no)
			(net "GND")
			(clearance 0)
		)
	)
	(footprint ""
		(layer "F.Cu")
		(at 472.175078 -79.810102)
		(property "Reference" "J11"
			(at -5.5118 -17.948148 0)
			(unlocked yes)
			(layer "F.SilkS")
			(effects
				(font
					(size 0.7874 0.5842)
					(thickness 0.1524)
				)
				(justify left)
			)
		)
		(property "Value" ""
			(at 0 0 0)
			(layer "F.Fab")
			(effects
				(font
					(size 1.27 1.27)
				)
			)
		)
		(duplicate_pad_numbers_are_jumpers no)
		(fp_line
			(start -5.530088 -17.210024)
			(end 1.720088 -17.210024)
			(stroke
				(width 0.1524)
				(type default)
			)
			(layer "F.SilkS")
		)
		(fp_line
			(start -5.530088 29.29001)
			(end -5.530088 -17.210024)
			(stroke
				(width 0.1524)
				(type default)
			)
			(layer "F.SilkS")
		)
		(fp_line
			(start 1.720088 -17.210024)
			(end 1.720088 29.29001)
			(stroke
				(width 0.1524)
				(type default)
			)
			(layer "F.SilkS")
		)
		(fp_line
			(start 1.720088 29.29001)
			(end -5.530088 29.29001)
			(stroke
				(width 0.1524)
				(type default)
			)
			(layer "F.SilkS")
		)
		(fp_poly
			(pts
				(xy 2.9464 0.508) (xy 2.9464 -0.508) (xy 1.9304 0)
			)
			(stroke
				(width 0)
				(type default)
			)
			(fill yes)
			(layer "F.SilkS")
		)
		(fp_line
			(start -5.530088 -17.210024)
			(end 1.720088 -17.210024)
			(stroke
				(width 0.1)
				(type default)
			)
			(layer "F.Fab")
		)
		(fp_line
			(start -5.530088 29.29001)
			(end -5.530088 -17.210024)
			(stroke
				(width 0.1)
				(type default)
			)
			(layer "F.Fab")
		)
		(fp_line
			(start 1.720088 -17.210024)
			(end 1.720088 29.29001)
			(stroke
				(width 0.1)
				(type default)
			)
			(layer "F.Fab")
		)
		(fp_line
			(start 1.720088 29.29001)
			(end -5.530088 29.29001)
			(stroke
				(width 0.1)
				(type default)
			)
			(layer "F.Fab")
		)
		(fp_poly
			(pts
				(xy 2.9464 0.508) (xy 2.9464 -0.508) (xy 1.9304 0)
			)
			(stroke
				(width 0)
				(type default)
			)
			(fill yes)
			(layer "F.Fab")
		)
		(pad "" np_thru_hole circle
			(at -1.905 23.82012 90)
			(size 2.1844 2.1844)
			(drill 2.1844)
			(layers "*.Cu" "*.Mask")
			(clearance 0.381)
			(thermal_gap 0.381)
		)
		(pad "" np_thru_hole circle
			(at -0.55499 -11.73988 90)
			(size 2.1844 2.1844)
			(drill 2.1844)
			(layers "*.Cu" "*.Mask")
			(clearance 0.381)
			(thermal_gap 0.381)
		)
		(pad "P1" thru_hole circle
			(at -0.55499 21.28012 90)
			(size 1.5494 1.5494)
			(drill 1.0414)
			(layers "*.Cu" "*.Mask")
			(remove_unused_layers no)
			(net "GND")
			(clearance 0)
		)
		(pad "P2" thru_hole circle
			(at -0.55499 18.74012 90)
			(size 1.5494 1.5494)
			(drill 1.0414)
			(layers "*.Cu" "*.Mask")
			(remove_unused_layers no)
			(net "GND")
			(clearance 0)
		)
		(pad "P3" thru_hole circle
			(at -0.55499 16.20012 90)
			(size 1.5494 1.5494)
			(drill 1.0414)
			(layers "*.Cu" "*.Mask")
			(remove_unused_layers no)
			(net "GND")
			(clearance 0)
		)
		(pad "P4" thru_hole circle
			(at -0.55499 13.66012 90)
			(size 1.5494 1.5494)
			(drill 1.0414)
			(layers "*.Cu" "*.Mask")
			(remove_unused_layers no)
			(net "GND")
			(clearance 0)
		)
		(pad "P5" thru_hole circle
			(at -0.55499 11.12012 90)
			(size 1.5494 1.5494)
			(drill 1.0414)
			(layers "*.Cu" "*.Mask")
			(remove_unused_layers no)
			(net "P52V_FAN")
			(clearance 0)
		)
		(pad "P6" thru_hole circle
			(at -0.55499 8.58012 90)
			(size 1.5494 1.5494)
			(drill 1.0414)
			(layers "*.Cu" "*.Mask")
			(remove_unused_layers no)
			(net "P52V_FAN")
			(clearance 0)
		)
		(pad "P7" thru_hole circle
			(at -0.55499 6.04012 90)
			(size 1.5494 1.5494)
			(drill 1.0414)
			(layers "*.Cu" "*.Mask")
			(remove_unused_layers no)
			(net "P52V_FAN")
			(clearance 0)
		)
		(pad "P8" thru_hole circle
			(at -0.55499 3.50012 90)
			(size 1.5494 1.5494)
			(drill 1.0414)
			(layers "*.Cu" "*.Mask")
			(remove_unused_layers no)
			(net "P52V_FAN")
			(clearance 0)
		)
		(pad "P9" thru_hole circle
			(at -3.25501 3.50012 90)
			(size 1.5494 1.5494)
			(drill 1.0414)
			(layers "*.Cu" "*.Mask")
			(remove_unused_layers no)
			(net "P52V_FAN")
			(clearance 0)
		)
		(pad "P10" thru_hole circle
			(at -3.25501 6.04012 90)
			(size 1.5494 1.5494)
			(drill 1.0414)
			(layers "*.Cu" "*.Mask")
			(remove_unused_layers no)
			(net "P52V_FAN")
			(clearance 0)
		)
		(pad "P11" thru_hole circle
			(at -3.25501 8.58012 90)
			(size 1.5494 1.5494)
			(drill 1.0414)
			(layers "*.Cu" "*.Mask")
			(remove_unused_layers no)
			(net "P52V_FAN")
			(clearance 0)
		)
		(pad "P12" thru_hole circle
			(at -3.25501 11.12012 90)
			(size 1.5494 1.5494)
			(drill 1.0414)
			(layers "*.Cu" "*.Mask")
			(remove_unused_layers no)
			(net "P52V_FAN")
			(clearance 0)
		)
		(pad "P13" thru_hole circle
			(at -3.25501 13.66012 90)
			(size 1.5494 1.5494)
			(drill 1.0414)
			(layers "*.Cu" "*.Mask")
			(remove_unused_layers no)
			(net "GND")
			(clearance 0)
		)
		(pad "P14" thru_hole circle
			(at -3.25501 16.20012 90)
			(size 1.5494 1.5494)
			(drill 1.0414)
			(layers "*.Cu" "*.Mask")
			(remove_unused_layers no)
			(net "GND")
			(clearance 0)
		)
		(pad "P15" thru_hole circle
			(at -3.25501 18.74012 90)
			(size 1.5494 1.5494)
			(drill 1.0414)
			(layers "*.Cu" "*.Mask")
			(remove_unused_layers no)
			(net "GND")
			(clearance 0)
		)
		(pad "P16" thru_hole circle
			(at -3.25501 21.28012 90)
			(size 1.5494 1.5494)
			(drill 1.0414)
			(layers "*.Cu" "*.Mask")
			(remove_unused_layers no)
			(net "GND")
			(clearance 0)
		)
		(pad "S1" thru_hole circle
			(at 0 0 90)
			(size 1.5494 1.5494)
			(drill 1.0414)
			(layers "*.Cu" "*.Mask")
			(remove_unused_layers no)
			(net "GND")
			(clearance 0)
		)
		(pad "S2" thru_hole circle
			(at -1.27 -1.27 90)
			(size 1.5494 1.5494)
			(drill 1.0414)
			(layers "*.Cu" "*.Mask")
			(remove_unused_layers no)
			(net "PWRGD_P3V3_HPDB")
			(clearance 0)
		)
		(pad "S3" thru_hole circle
			(at 0 -2.54 90)
			(size 1.5494 1.5494)
			(drill 1.0414)
			(layers "*.Cu" "*.Mask")
			(remove_unused_layers no)
			(net "GND")
			(clearance 0)
		)
		(pad "S4" thru_hole circle
			(at -1.27 -3.81 90)
			(size 1.5494 1.5494)
			(drill 1.0414)
			(layers "*.Cu" "*.Mask")
			(remove_unused_layers no)
			(net "PWRGD_P52V_HS_PG")
			(clearance 0)
		)
		(pad "S5" thru_hole circle
			(at 0 -5.08 90)
			(size 1.5494 1.5494)
			(drill 1.0414)
			(layers "*.Cu" "*.Mask")
			(remove_unused_layers no)
			(net "SMB_P52V_R_SDA")
			(clearance 0)
		)
		(pad "S6" thru_hole circle
			(at -1.27 -6.35 90)
			(size 1.5494 1.5494)
			(drill 1.0414)
			(layers "*.Cu" "*.Mask")
			(remove_unused_layers no)
			(net "SMB_P52V_R_SCL")
			(clearance 0)
		)
		(pad "S7" thru_hole circle
			(at 0 -7.62 90)
			(size 1.5494 1.5494)
			(drill 1.0414)
			(layers "*.Cu" "*.Mask")
			(remove_unused_layers no)
			(net "SMB_PDB_R_SDA")
			(clearance 0)
		)
		(pad "S8" thru_hole circle
			(at -1.27 -8.89 90)
			(size 1.5494 1.5494)
			(drill 1.0414)
			(layers "*.Cu" "*.Mask")
			(remove_unused_layers no)
			(net "SMB_PDB_R_SCL")
			(clearance 0)
		)
		(pad "S9" thru_hole circle
			(at -3.81 -8.89 90)
			(size 1.5494 1.5494)
			(drill 1.0414)
			(layers "*.Cu" "*.Mask")
			(remove_unused_layers no)
			(net "P12V_HPDB")
			(clearance 0)
		)
		(pad "S10" thru_hole circle
			(at -2.54 -7.62 90)
			(size 1.5494 1.5494)
			(drill 1.0414)
			(layers "*.Cu" "*.Mask")
			(remove_unused_layers no)
			(net "P12V_HPDB")
			(clearance 0)
		)
		(pad "S11" thru_hole circle
			(at -3.81 -6.35 90)
			(size 1.5494 1.5494)
			(drill 1.0414)
			(layers "*.Cu" "*.Mask")
			(remove_unused_layers no)
			(net "PWRGD_P3V3_AUX_MB_BUF")
			(clearance 0)
		)
		(pad "S12" thru_hole circle
			(at -2.54 -5.08 90)
			(size 1.5494 1.5494)
			(drill 1.0414)
			(layers "*.Cu" "*.Mask")
			(remove_unused_layers no)
			(net "FAN_PWR_EN_BUF")
			(clearance 0)
		)
		(pad "S13" thru_hole circle
			(at -3.81 -3.81 90)
			(size 1.5494 1.5494)
			(drill 1.0414)
			(layers "*.Cu" "*.Mask")
			(remove_unused_layers no)
			(net "P12V_HPDB")
			(clearance 0)
		)
		(pad "S14" thru_hole circle
			(at -2.54 -2.54 90)
			(size 1.5494 1.5494)
			(drill 1.0414)
			(layers "*.Cu" "*.Mask")
			(remove_unused_layers no)
			(net "GPU_HSC_EN")
			(clearance 0)
		)
		(pad "S15" thru_hole circle
			(at -3.81 -1.27 90)
			(size 1.5494 1.5494)
			(drill 1.0414)
			(layers "*.Cu" "*.Mask")
			(remove_unused_layers no)
			(net "RST_SMB_PDB_BUF_N")
			(clearance 0)
		)
		(pad "S16" thru_hole circle
			(at -2.54 0 90)
			(size 1.5494 1.5494)
			(drill 1.0414)
			(layers "*.Cu" "*.Mask")
			(remove_unused_layers no)
			(net "P12V_HPDB_PWRGD")
			(clearance 0)
		)
		(zone
			(layers "F.Cu" "B.Cu" "In1.Cu" "In2.Cu" "In3.Cu" "In4.Cu" "In5.Cu" "In6.Cu"
				"In7.Cu" "In8.Cu"
			)
			(hatch none 0.5)
			(connect_pads
				(clearance 0)
			)
			(min_thickness 0.25)
			(keepout
				(tracks not_allowed)
				(vias allowed)
				(pads allowed)
				(copperpour not_allowed)
				(footprints allowed)
			)
			(placement
				(enabled no)
				(sheetname "")
			)
			(fill
				(thermal_gap 0.5)
				(thermal_bridge_width 0.5)
				(island_removal_mode 0)
			)
			(polygon
				(pts
					(arc
						(start 471.870278 -55.989982)
						(mid 468.669878 -55.989982)
						(end 471.870278 -55.989982)
					)
				)
			)
		)
		(zone
			(layers "F.Cu" "B.Cu" "In1.Cu" "In2.Cu" "In3.Cu" "In4.Cu" "In5.Cu" "In6.Cu"
				"In7.Cu" "In8.Cu"
			)
			(hatch none 0.5)
			(connect_pads
				(clearance 0)
			)
			(min_thickness 0.25)
			(keepout
				(tracks not_allowed)
				(vias allowed)
				(pads allowed)
				(copperpour not_allowed)
				(footprints allowed)
			)
			(placement
				(enabled no)
				(sheetname "")
			)
			(fill
				(thermal_gap 0.5)
				(thermal_bridge_width 0.5)
				(island_removal_mode 0)
			)
			(polygon
				(pts
					(arc
						(start 473.220288 -91.549982)
						(mid 470.019888 -91.549982)
						(end 473.220288 -91.549982)
					)
				)
			)
		)
	)
	(footprint ""
		(layer "F.Cu")
		(at 261.1374 -48.387)
		(property "Reference" "R154"
			(at 0 0 0)
			(layer "F.SilkS")
			(hide yes)
			(effects
				(font
					(size 1.27 1.27)
				)
			)
		)
		(property "Value" ""
			(at 0 0 0)
			(layer "F.Fab")
			(effects
				(font
					(size 1.27 1.27)
				)
			)
		)
		(duplicate_pad_numbers_are_jumpers no)
		(fp_line
			(start -1.651 -0.8382)
			(end 1.651 -0.8382)
			(stroke
				(width 0.1524)
				(type default)
			)
			(layer "F.SilkS")
		)
		(fp_line
			(start -1.651 0.8382)
			(end -1.651 -0.8382)
			(stroke
				(width 0.1524)
				(type default)
			)
			(layer "F.SilkS")
		)
		(fp_line
			(start 1.651 -0.8382)
			(end 1.651 0.8382)
			(stroke
				(width 0.1524)
				(type default)
			)
			(layer "F.SilkS")
		)
		(fp_line
			(start 1.651 0.8382)
			(end -1.651 0.8382)
			(stroke
				(width 0.1524)
				(type default)
			)
			(layer "F.SilkS")
		)
		(fp_line
			(start -1.559814 -0.7366)
			(end -1.559814 0.7366)
			(stroke
				(width 0.1)
				(type default)
			)
			(layer "F.Fab")
		)
		(fp_line
			(start -1.559814 0.7366)
			(end -1.524 0.7366)
			(stroke
				(width 0.1)
				(type default)
			)
			(layer "F.Fab")
		)
		(fp_line
			(start -1.524 -0.7366)
			(end -1.559814 -0.7366)
			(stroke
				(width 0.1)
				(type default)
			)
			(layer "F.Fab")
		)
		(fp_line
			(start -1.524 0.7366)
			(end 1.524 0.7366)
			(stroke
				(width 0.1)
				(type default)
			)
			(layer "F.Fab")
		)
		(fp_line
			(start 1.524 -0.7366)
			(end -1.524 -0.7366)
			(stroke
				(width 0.1)
				(type default)
			)
			(layer "F.Fab")
		)
		(fp_line
			(start 1.524 0.7366)
			(end 1.560576 0.7366)
			(stroke
				(width 0.1)
				(type default)
			)
			(layer "F.Fab")
		)
		(fp_line
			(start 1.560576 -0.7366)
			(end 1.524 -0.7366)
			(stroke
				(width 0.1)
				(type default)
			)
			(layer "F.Fab")
		)
		(fp_line
			(start 1.560576 0.7366)
			(end 1.560576 -0.7366)
			(stroke
				(width 0.1)
				(type default)
			)
			(layer "F.Fab")
		)
		(pad "1" smd rect
			(at -0.94996 0 180)
			(size 1.1176 1.3716)
			(layers "F.Cu" "F.Mask" "F.Paste")
			(net "P52V_1_FUSE_1")
		)
		(pad "2" smd rect
			(at 0.94996 0 180)
			(size 1.1176 1.3716)
			(layers "F.Cu" "F.Mask" "F.Paste")
			(net "GPU_HSC1_BUF_EN_N")
		)
	)
	(footprint ""
		(layer "F.Cu")
		(at 438.023 -44.45 180)
		(property "Reference" "R381"
			(at 0 0 180)
			(layer "F.SilkS")
			(hide yes)
			(effects
				(font
					(size 1.27 1.27)
				)
			)
		)
		(property "Value" ""
			(at 0 0 180)
			(layer "F.Fab")
			(effects
				(font
					(size 1.27 1.27)
				)
			)
		)
		(duplicate_pad_numbers_are_jumpers no)
		(fp_line
			(start 0.7874 0.4064)
			(end -0.7874 0.4064)
			(stroke
				(width 0.1524)
				(type default)
			)
			(layer "F.SilkS")
		)
		(fp_line
			(start 0.7874 -0.4064)
			(end 0.7874 0.4064)
			(stroke
				(width 0.1524)
				(type default)
			)
			(layer "F.SilkS")
		)
		(fp_line
			(start -0.7874 0.4064)
			(end -0.7874 -0.4064)
			(stroke
				(width 0.1524)
				(type default)
			)
			(layer "F.SilkS")
		)
		(fp_line
			(start -0.7874 -0.4064)
			(end 0.7874 -0.4064)
			(stroke
				(width 0.1524)
				(type default)
			)
			(layer "F.SilkS")
		)
		(fp_line
			(start 0.67945 0.3048)
			(end 0.120396 0.3048)
			(stroke
				(width 0.1)
				(type default)
			)
			(layer "F.Fab")
		)
		(fp_line
			(start 0.67945 -0.3048)
			(end 0.67945 0.3048)
			(stroke
				(width 0.1)
				(type default)
			)
			(layer "F.Fab")
		)
		(fp_line
			(start 0.12065 -0.2794)
			(end 0.12065 -0.3048)
			(stroke
				(width 0.1)
				(type default)
			)
			(layer "F.Fab")
		)
		(fp_line
			(start 0.12065 -0.3048)
			(end 0.67945 -0.3048)
			(stroke
				(width 0.1)
				(type default)
			)
			(layer "F.Fab")
		)
		(fp_line
			(start 0.120396 0.3048)
			(end 0.120396 0.2794)
			(stroke
				(width 0.1)
				(type default)
			)
			(layer "F.Fab")
		)
		(fp_line
			(start 0.120396 0.2794)
			(end -0.12065 0.2794)
			(stroke
				(width 0.1)
				(type default)
			)
			(layer "F.Fab")
		)
		(fp_line
			(start -0.12065 0.3048)
			(end -0.67945 0.3048)
			(stroke
				(width 0.1)
				(type default)
			)
			(layer "F.Fab")
		)
		(fp_line
			(start -0.12065 0.2794)
			(end -0.12065 0.3048)
			(stroke
				(width 0.1)
				(type default)
			)
			(layer "F.Fab")
		)
		(fp_line
			(start -0.12065 -0.2794)
			(end 0.12065 -0.2794)
			(stroke
				(width 0.1)
				(type default)
			)
			(layer "F.Fab")
		)
		(fp_line
			(start -0.12065 -0.305054)
			(end -0.12065 -0.2794)
			(stroke
				(width 0.1)
				(type default)
			)
			(layer "F.Fab")
		)
		(fp_line
			(start -0.67945 0.3048)
			(end -0.67945 -0.305054)
			(stroke
				(width 0.1)
				(type default)
			)
			(layer "F.Fab")
		)
		(fp_line
			(start -0.67945 -0.305054)
			(end -0.12065 -0.305054)
			(stroke
				(width 0.1)
				(type default)
			)
			(layer "F.Fab")
		)
		(pad "1" smd circle
			(at -0.40005 0 180)
			(size 0 0)
			(layers "F.Cu" "F.Mask" "F.Paste")
			(net "GPU_HSC_EN")
		)
		(pad "2" smd circle
			(at 0.40005 0 180)
			(size 0 0)
			(layers "F.Cu" "F.Mask" "F.Paste")
			(net "P3V3_AUX")
		)
	)
)
